(kicad_pcb
	(version 20260206)
	(generator "pcbnew")
	(generator_version "10.0")
	(general
		(thickness 1.6)
		(legacy_teardrops no)
	)
	(paper "A4")
	(title_block
		(title "pdpb — Lightning_PDPB_BRD.brd")
		(comment 1 "Lightning (Wiwynn / Facebook NVMe JBOF) / footprints 513-519 of 1140")
	)
	(layers
		(0 "F.Cu" signal "TOP")
		(4 "In1.Cu" signal "L2GND")
		(6 "In2.Cu" signal "L3")
		(8 "In3.Cu" signal "L4VCC")
		(10 "In4.Cu" signal "L5VCC")
		(12 "In5.Cu" signal "L6")
		(14 "In6.Cu" signal "L7GND")
		(2 "B.Cu" signal "BOTTOM")
		(9 "F.Adhes" user "F.Adhesive")
		(11 "B.Adhes" user "B.Adhesive")
		(13 "F.Paste" user "Package Geometry/Pastemask Top")
		(15 "B.Paste" user "Package Geometry/Pastemask Bottom")
		(5 "F.SilkS" user "Ref Des/Silkscreen Top")
		(7 "B.SilkS" user "Ref Des/Silkscreen Bottom")
		(1 "F.Mask" user "Board Geometry/Soldermask Top")
		(3 "B.Mask" user "Board Geometry/Soldermask Bottom")
		(17 "Dwgs.User" user "User.Drawings")
		(19 "Cmts.User" user "User.Comments")
		(21 "Eco1.User" user "User.Eco1")
		(23 "Eco2.User" user "User.Eco2")
		(25 "Edge.Cuts" user "Board Geometry/Outline")
		(27 "Margin" user)
		(31 "F.CrtYd" user "Package Geometry/Place Bound Top")
		(29 "B.CrtYd" user "Package Geometry/Place Bound Bottom")
		(35 "F.Fab" user "Ref Des/Assembly Top")
		(33 "B.Fab" user "Ref Des/Assembly Bottom")
	)
	(footprint ""
		(layer "F.Cu")
		(at 32.131 -288.798 -90)
		(property "Reference" "R402"
			(at 0 0 270)
			(layer "F.SilkS")
			(hide yes)
			(effects
				(font
					(size 1.27 1.27)
				)
			)
		)
		(property "Value" "0R2J-2-GP"
			(at 0.064008 -3.993896 270)
			(unlocked yes)
			(layer "F.Fab")
			(hide yes)
			(effects
				(font
					(size 1.016 1.016)
					(thickness 0.1524)
				)
			)
		)
		(property "Device Type" "R402H16"
			(at 0.064008 -5.517896 270)
			(unlocked yes)
			(layer "F.Fab")
			(hide yes)
			(effects
				(font
					(size 1.016 1.016)
					(thickness 0.1524)
				)
			)
		)
		(duplicate_pad_numbers_are_jumpers no)
		(fp_line
			(start -0.508 -0.9398)
			(end -0.508 0.9398)
			(stroke
				(width 0.1524)
				(type default)
			)
			(layer "F.SilkS")
		)
		(fp_line
			(start 0.508 -0.9398)
			(end -0.508 -0.9398)
			(stroke
				(width 0.1524)
				(type default)
			)
			(layer "F.SilkS")
		)
		(fp_rect
			(start -0.508 0.9398)
			(end 0.508 -0.9398)
			(stroke
				(width 0)
				(type default)
			)
			(fill no)
			(layer "F.CrtYd")
		)
		(fp_rect
			(start -0.508 0.9398)
			(end 0.508 -0.9398)
			(stroke
				(width 0)
				(type default)
			)
			(fill no)
			(layer "F.Fab")
		)
		(pad "1" smd custom
			(at 0 -0.4445 270)
			(size 0.1397 0.1397)
			(layers "F.Cu" "F.Mask" "F.Paste")
			(net "SDA_DR7_R")
			(options
				(clearance outline)
				(anchor circle)
			)
			(primitives
				(gr_poly
					(pts
						(arc
							(start -0.1778 -0.2794)
							(mid -0.249642 -0.249642)
							(end -0.2794 -0.1778)
						)
						(arc
							(start -0.2794 0.1778)
							(mid -0.249642 0.249642)
							(end -0.1778 0.2794)
						)
						(arc
							(start 0.1778 0.2794)
							(mid 0.249642 0.249642)
							(end 0.2794 0.1778)
						)
						(arc
							(start 0.2794 -0.1778)
							(mid 0.249642 -0.249642)
							(end 0.1778 -0.2794)
						)
					)
					(width 0)
					(fill yes)
				)
			)
		)
		(pad "2" smd custom
			(at 0 0.4445 270)
			(size 0.1397 0.1397)
			(layers "F.Cu" "F.Mask" "F.Paste")
			(net "SDA_DR7")
			(options
				(clearance outline)
				(anchor circle)
			)
			(primitives
				(gr_poly
					(pts
						(arc
							(start -0.1778 -0.2794)
							(mid -0.249642 -0.249642)
							(end -0.2794 -0.1778)
						)
						(arc
							(start -0.2794 0.1778)
							(mid -0.249642 0.249642)
							(end -0.1778 0.2794)
						)
						(arc
							(start 0.1778 0.2794)
							(mid 0.249642 0.249642)
							(end 0.2794 0.1778)
						)
						(arc
							(start 0.2794 -0.1778)
							(mid 0.249642 -0.249642)
							(end 0.1778 -0.2794)
						)
					)
					(width 0)
					(fill yes)
				)
			)
		)
	)
	(footprint ""
		(layer "F.Cu")
		(at 234.061 -144.77111 -90)
		(property "Reference" "R9442"
			(at 0 0 270)
			(layer "F.SilkS")
			(hide yes)
			(effects
				(font
					(size 1.27 1.27)
				)
			)
		)
		(property "Value" "330R2F-GP"
			(at 0.064008 -3.993896 270)
			(unlocked yes)
			(layer "F.Fab")
			(hide yes)
			(effects
				(font
					(size 1.016 1.016)
					(thickness 0.1524)
				)
			)
		)
		(property "Device Type" "R402H16"
			(at 0.064008 -5.517896 270)
			(unlocked yes)
			(layer "F.Fab")
			(hide yes)
			(effects
				(font
					(size 1.016 1.016)
					(thickness 0.1524)
				)
			)
		)
		(duplicate_pad_numbers_are_jumpers no)
		(fp_line
			(start -0.508 -0.9398)
			(end -0.508 0.9398)
			(stroke
				(width 0.1524)
				(type default)
			)
			(layer "F.SilkS")
		)
		(fp_line
			(start 0.508 -0.9398)
			(end -0.508 -0.9398)
			(stroke
				(width 0.1524)
				(type default)
			)
			(layer "F.SilkS")
		)
		(fp_rect
			(start -0.508 0.9398)
			(end 0.508 -0.9398)
			(stroke
				(width 0)
				(type default)
			)
			(fill no)
			(layer "F.CrtYd")
		)
		(fp_rect
			(start -0.508 0.9398)
			(end 0.508 -0.9398)
			(stroke
				(width 0)
				(type default)
			)
			(fill no)
			(layer "F.Fab")
		)
		(pad "1" smd custom
			(at 0 -0.4445 270)
			(size 0.1397 0.1397)
			(layers "F.Cu" "F.Mask" "F.Paste")
			(net "P3V3")
			(options
				(clearance outline)
				(anchor circle)
			)
			(primitives
				(gr_poly
					(pts
						(arc
							(start -0.1778 -0.2794)
							(mid -0.249642 -0.249642)
							(end -0.2794 -0.1778)
						)
						(arc
							(start -0.2794 0.1778)
							(mid -0.249642 0.249642)
							(end -0.1778 0.2794)
						)
						(arc
							(start 0.1778 0.2794)
							(mid 0.249642 0.249642)
							(end 0.2794 0.1778)
						)
						(arc
							(start 0.2794 -0.1778)
							(mid 0.249642 -0.249642)
							(end 0.1778 -0.2794)
						)
					)
					(width 0)
					(fill yes)
				)
			)
		)
		(pad "2" smd custom
			(at 0 0.4445 270)
			(size 0.1397 0.1397)
			(layers "F.Cu" "F.Mask" "F.Paste")
			(net "DRV_ATTN_3")
			(options
				(clearance outline)
				(anchor circle)
			)
			(primitives
				(gr_poly
					(pts
						(arc
							(start -0.1778 -0.2794)
							(mid -0.249642 -0.249642)
							(end -0.2794 -0.1778)
						)
						(arc
							(start -0.2794 0.1778)
							(mid -0.249642 0.249642)
							(end -0.1778 0.2794)
						)
						(arc
							(start 0.1778 0.2794)
							(mid 0.249642 0.249642)
							(end 0.2794 0.1778)
						)
						(arc
							(start 0.2794 -0.1778)
							(mid 0.249642 -0.249642)
							(end 0.1778 -0.2794)
						)
					)
					(width 0)
					(fill yes)
				)
			)
		)
	)
	(footprint ""
		(layer "F.Cu")
		(at 82.931 -310.515 90)
		(property "Reference" "SR948"
			(at 0 0 90)
			(layer "F.SilkS")
			(hide yes)
			(effects
				(font
					(size 1.27 1.27)
				)
			)
		)
		(property "Value" "4K7R2F-GP"
			(at 0.064008 -3.993896 90)
			(unlocked yes)
			(layer "F.Fab")
			(hide yes)
			(effects
				(font
					(size 1.016 1.016)
					(thickness 0.1524)
				)
			)
		)
		(property "Device Type" "R402H16"
			(at 0.064008 -5.517896 90)
			(unlocked yes)
			(layer "F.Fab")
			(hide yes)
			(effects
				(font
					(size 1.016 1.016)
					(thickness 0.1524)
				)
			)
		)
		(duplicate_pad_numbers_are_jumpers no)
		(fp_line
			(start 0.508 -0.9398)
			(end -0.508 -0.9398)
			(stroke
				(width 0.1524)
				(type default)
			)
			(layer "F.SilkS")
		)
		(fp_line
			(start -0.508 -0.9398)
			(end -0.508 0.9398)
			(stroke
				(width 0.1524)
				(type default)
			)
			(layer "F.SilkS")
		)
		(fp_rect
			(start -0.508 0.9398)
			(end 0.508 -0.9398)
			(stroke
				(width 0)
				(type default)
			)
			(fill no)
			(layer "F.CrtYd")
		)
		(fp_rect
			(start -0.508 0.9398)
			(end 0.508 -0.9398)
			(stroke
				(width 0)
				(type default)
			)
			(fill no)
			(layer "F.Fab")
		)
		(pad "1" smd custom
			(at 0 -0.4445 90)
			(size 0.1397 0.1397)
			(layers "F.Cu" "F.Mask" "F.Paste")
			(net "VDD_DIFF_2")
			(options
				(clearance outline)
				(anchor circle)
			)
			(primitives
				(gr_poly
					(pts
						(arc
							(start -0.1778 -0.2794)
							(mid -0.249642 -0.249642)
							(end -0.2794 -0.1778)
						)
						(arc
							(start -0.2794 0.1778)
							(mid -0.249642 0.249642)
							(end -0.1778 0.2794)
						)
						(arc
							(start 0.1778 0.2794)
							(mid 0.249642 0.249642)
							(end 0.2794 0.1778)
						)
						(arc
							(start 0.2794 -0.1778)
							(mid 0.249642 -0.249642)
							(end 0.1778 -0.2794)
						)
					)
					(width 0)
					(fill yes)
				)
			)
		)
		(pad "2" smd custom
			(at 0 0.4445 90)
			(size 0.1397 0.1397)
			(layers "F.Cu" "F.Mask" "F.Paste")
			(net "CLK_BUF_EU2_100M_133M#")
			(options
				(clearance outline)
				(anchor circle)
			)
			(primitives
				(gr_poly
					(pts
						(arc
							(start -0.1778 -0.2794)
							(mid -0.249642 -0.249642)
							(end -0.2794 -0.1778)
						)
						(arc
							(start -0.2794 0.1778)
							(mid -0.249642 0.249642)
							(end -0.1778 0.2794)
						)
						(arc
							(start 0.1778 0.2794)
							(mid 0.249642 0.249642)
							(end 0.2794 0.1778)
						)
						(arc
							(start 0.2794 -0.1778)
							(mid 0.249642 -0.249642)
							(end 0.1778 -0.2794)
						)
					)
					(width 0)
					(fill yes)
				)
			)
		)
	)
	(footprint ""
		(layer "F.Cu")
		(at 73.80732 -143.256 180)
		(property "Reference" "SR964"
			(at 0 0 180)
			(layer "F.SilkS")
			(hide yes)
			(effects
				(font
					(size 1.27 1.27)
				)
			)
		)
		(property "Value" "2KR2F-3-GP"
			(at 0.064008 -3.993896 180)
			(unlocked yes)
			(layer "F.Fab")
			(hide yes)
			(effects
				(font
					(size 1.016 1.016)
					(thickness 0.1524)
				)
			)
		)
		(property "Device Type" "R402H16"
			(at 0.064008 -5.517896 180)
			(unlocked yes)
			(layer "F.Fab")
			(hide yes)
			(effects
				(font
					(size 1.016 1.016)
					(thickness 0.1524)
				)
			)
		)
		(duplicate_pad_numbers_are_jumpers no)
		(fp_line
			(start 0.508 -0.9398)
			(end -0.508 -0.9398)
			(stroke
				(width 0.1524)
				(type default)
			)
			(layer "F.SilkS")
		)
		(fp_line
			(start -0.508 -0.9398)
			(end -0.508 0.9398)
			(stroke
				(width 0.1524)
				(type default)
			)
			(layer "F.SilkS")
		)
		(fp_rect
			(start -0.508 0.9398)
			(end 0.508 -0.9398)
			(stroke
				(width 0)
				(type default)
			)
			(fill no)
			(layer "F.CrtYd")
		)
		(fp_rect
			(start -0.508 0.9398)
			(end 0.508 -0.9398)
			(stroke
				(width 0)
				(type default)
			)
			(fill no)
			(layer "F.Fab")
		)
		(pad "1" smd custom
			(at 0 -0.4445 180)
			(size 0.1397 0.1397)
			(layers "F.Cu" "F.Mask" "F.Paste")
			(net "P3V3")
			(options
				(clearance outline)
				(anchor circle)
			)
			(primitives
				(gr_poly
					(pts
						(arc
							(start -0.1778 -0.2794)
							(mid -0.249642 -0.249642)
							(end -0.2794 -0.1778)
						)
						(arc
							(start -0.2794 0.1778)
							(mid -0.249642 0.249642)
							(end -0.1778 0.2794)
						)
						(arc
							(start 0.1778 0.2794)
							(mid 0.249642 0.249642)
							(end 0.2794 0.1778)
						)
						(arc
							(start 0.2794 -0.1778)
							(mid 0.249642 -0.249642)
							(end 0.1778 -0.2794)
						)
					)
					(width 0)
					(fill yes)
				)
			)
		)
		(pad "2" smd custom
			(at 0 0.4445 180)
			(size 0.1397 0.1397)
			(layers "F.Cu" "F.Mask" "F.Paste")
			(net "SDA_DR14")
			(options
				(clearance outline)
				(anchor circle)
			)
			(primitives
				(gr_poly
					(pts
						(arc
							(start -0.1778 -0.2794)
							(mid -0.249642 -0.249642)
							(end -0.2794 -0.1778)
						)
						(arc
							(start -0.2794 0.1778)
							(mid -0.249642 0.249642)
							(end -0.1778 0.2794)
						)
						(arc
							(start 0.1778 0.2794)
							(mid 0.249642 0.249642)
							(end 0.2794 0.1778)
						)
						(arc
							(start 0.2794 -0.1778)
							(mid 0.249642 -0.249642)
							(end 0.1778 -0.2794)
						)
					)
					(width 0)
					(fill yes)
				)
			)
		)
	)
	(footprint ""
		(layer "F.Cu")
		(at 209.804 -294.64 -90)
		(property "Reference" "R139"
			(at 0 0 270)
			(layer "F.SilkS")
			(hide yes)
			(effects
				(font
					(size 1.27 1.27)
				)
			)
		)
		(property "Value" "4K7R2J-2-GP"
			(at 0.064008 -3.993896 270)
			(unlocked yes)
			(layer "F.Fab")
			(hide yes)
			(effects
				(font
					(size 1.016 1.016)
					(thickness 0.1524)
				)
			)
		)
		(property "Device Type" "R402H16"
			(at 0.064008 -5.517896 270)
			(unlocked yes)
			(layer "F.Fab")
			(hide yes)
			(effects
				(font
					(size 1.016 1.016)
					(thickness 0.1524)
				)
			)
		)
		(duplicate_pad_numbers_are_jumpers no)
		(fp_line
			(start -0.508 -0.9398)
			(end -0.508 0.9398)
			(stroke
				(width 0.1524)
				(type default)
			)
			(layer "F.SilkS")
		)
		(fp_line
			(start 0.508 -0.9398)
			(end -0.508 -0.9398)
			(stroke
				(width 0.1524)
				(type default)
			)
			(layer "F.SilkS")
		)
		(fp_rect
			(start -0.508 0.9398)
			(end 0.508 -0.9398)
			(stroke
				(width 0)
				(type default)
			)
			(fill no)
			(layer "F.CrtYd")
		)
		(fp_rect
			(start -0.508 0.9398)
			(end 0.508 -0.9398)
			(stroke
				(width 0)
				(type default)
			)
			(fill no)
			(layer "F.Fab")
		)
		(pad "1" smd custom
			(at 0 -0.4445 270)
			(size 0.1397 0.1397)
			(layers "F.Cu" "F.Mask" "F.Paste")
			(net "P12V")
			(options
				(clearance outline)
				(anchor circle)
			)
			(primitives
				(gr_poly
					(pts
						(arc
							(start -0.1778 -0.2794)
							(mid -0.249642 -0.249642)
							(end -0.2794 -0.1778)
						)
						(arc
							(start -0.2794 0.1778)
							(mid -0.249642 0.249642)
							(end -0.1778 0.2794)
						)
						(arc
							(start 0.1778 0.2794)
							(mid 0.249642 0.249642)
							(end 0.2794 0.1778)
						)
						(arc
							(start 0.2794 -0.1778)
							(mid 0.249642 -0.249642)
							(end 0.1778 -0.2794)
						)
					)
					(width 0)
					(fill yes)
				)
			)
		)
		(pad "2" smd custom
			(at 0 0.4445 270)
			(size 0.1397 0.1397)
			(layers "F.Cu" "F.Mask" "F.Paste")
			(net "SW_SSD2_R")
			(options
				(clearance outline)
				(anchor circle)
			)
			(primitives
				(gr_poly
					(pts
						(arc
							(start -0.1778 -0.2794)
							(mid -0.249642 -0.249642)
							(end -0.2794 -0.1778)
						)
						(arc
							(start -0.2794 0.1778)
							(mid -0.249642 0.249642)
							(end -0.1778 0.2794)
						)
						(arc
							(start 0.1778 0.2794)
							(mid 0.249642 0.249642)
							(end 0.2794 0.1778)
						)
						(arc
							(start 0.2794 -0.1778)
							(mid 0.249642 -0.249642)
							(end 0.1778 -0.2794)
						)
					)
					(width 0)
					(fill yes)
				)
			)
		)
	)
	(footprint ""
		(layer "F.Cu")
		(at 228.499924 -247.10009)
		(property "Reference" "LED2"
			(at 0 0 0)
			(layer "F.SilkS")
			(hide yes)
			(effects
				(font
					(size 1.27 1.27)
				)
			)
		)
		(property "Value" "LED-RB-4-GP"
			(at 5.88899 1.80848 0)
			(unlocked yes)
			(layer "F.Fab")
			(hide yes)
			(effects
				(font
					(size 1.016 1.016)
					(thickness 0.1524)
				)
			)
		)
		(property "Device Type" "LED1613-4PH20"
			(at 5.88899 0.28448 0)
			(unlocked yes)
			(layer "F.Fab")
			(hide yes)
			(effects
				(font
					(size 1.016 1.016)
					(thickness 0.1524)
				)
			)
		)
		(duplicate_pad_numbers_are_jumpers no)
		(fp_line
			(start -1.4478 -0.9652)
			(end 1.4478 -0.9652)
			(stroke
				(width 0.1524)
				(type default)
			)
			(layer "F.SilkS")
		)
		(fp_line
			(start -1.4478 0.9652)
			(end -1.4478 -0.9652)
			(stroke
				(width 0.1524)
				(type default)
			)
			(layer "F.SilkS")
		)
		(fp_line
			(start -1.4478 0.9652)
			(end -1.4478 -0.9652)
			(stroke
				(width 0.508)
				(type default)
			)
			(layer "F.SilkS")
		)
		(fp_line
			(start 1.4478 -0.9652)
			(end 1.4478 0.9652)
			(stroke
				(width 0.1524)
				(type default)
			)
			(layer "F.SilkS")
		)
		(fp_line
			(start 1.4478 0.9652)
			(end -1.4478 0.9652)
			(stroke
				(width 0.1524)
				(type default)
			)
			(layer "F.SilkS")
		)
		(fp_rect
			(start -0.8001 0.6477)
			(end 0.8001 -0.6477)
			(stroke
				(width 0)
				(type default)
			)
			(fill no)
			(layer "F.CrtYd")
		)
		(fp_poly
			(pts
				(xy -1.7018 1.2192) (xy -1.7018 -0.06223) (xy -0.8001 -0.06223) (xy -0.8001 0.6477) (xy 0.8001 0.6477)
				(xy 0.8001 -0.6477) (xy -0.8001 -0.6477) (xy -0.8001 -0.0635) (xy -1.7018 -0.0635) (xy -1.7018 -1.2192)
				(xy 1.7018 -1.2192) (xy 1.7018 1.2192)
			)
			(stroke
				(width 0)
				(type default)
			)
			(fill no)
			(layer "F.CrtYd")
		)
		(fp_rect
			(start -1.7018 1.2192)
			(end 1.7018 -1.2192)
			(stroke
				(width 0)
				(type default)
			)
			(fill no)
			(layer "F.Fab")
		)
		(pad "1" smd rect
			(at -0.73025 0.4064)
			(size 0.9144 0.6096)
			(layers "F.Cu" "F.Mask" "F.Paste")
			(net "SSD_ACT_DR2_MOS_N")
		)
		(pad "2" smd rect
			(at -0.73025 -0.4064)
			(size 0.9144 0.6096)
			(layers "F.Cu" "F.Mask" "F.Paste")
			(net "ATTN_LED_DR2_MOS_N")
		)
		(pad "3" smd rect
			(at 0.73025 -0.4064)
			(size 0.9144 0.6096)
			(layers "F.Cu" "F.Mask" "F.Paste")
			(net "DRV_ATTN_2")
		)
		(pad "4" smd rect
			(at 0.73025 0.4064)
			(size 0.9144 0.6096)
			(layers "F.Cu" "F.Mask" "F.Paste")
			(net "DRV_ACT_2")
		)
	)
	(footprint ""
		(layer "F.Cu")
		(at 87.503 -102.743 180)
		(property "Reference" "C8934"
			(at 0 0 180)
			(layer "F.SilkS")
			(hide yes)
			(effects
				(font
					(size 1.27 1.27)
				)
			)
		)
		(property "Value" "SCD1U16V2KX-3GP"
			(at 1.1811 -2.7051 180)
			(unlocked yes)
			(layer "F.Fab")
			(hide yes)
			(effects
				(font
					(size 1.016 1.016)
					(thickness 0.1524)
				)
			)
		)
		(property "Device Type" "C402H22"
			(at 1.1811 -4.2291 180)
			(unlocked yes)
			(layer "F.Fab")
			(hide yes)
			(effects
				(font
					(size 1.016 1.016)
					(thickness 0.1524)
				)
			)
		)
		(duplicate_pad_numbers_are_jumpers no)
		(fp_rect
			(start -0.4318 0.9525)
			(end 0.4318 -0.9525)
			(stroke
				(width 0)
				(type default)
			)
			(fill no)
			(layer "F.CrtYd")
		)
		(fp_rect
			(start -0.4318 0.9525)
			(end 0.4318 -0.9525)
			(stroke
				(width 0)
				(type default)
			)
			(fill no)
			(layer "F.Fab")
		)
		(pad "1" smd custom
			(at 0 -0.4445 180)
			(size 0.1524 0.1524)
			(layers "F.Cu" "F.Mask" "F.Paste")
			(net "VDDR_4")
			(options
				(clearance outline)
				(anchor circle)
			)
			(primitives
				(gr_poly
					(pts
						(arc
							(start 0.3048 -0.2032)
							(mid 0.275042 -0.275042)
							(end 0.2032 -0.3048)
						)
						(arc
							(start -0.2032 -0.3048)
							(mid -0.275042 -0.275042)
							(end -0.3048 -0.2032)
						)
						(arc
							(start -0.3048 0.2032)
							(mid -0.275042 0.275042)
							(end -0.2032 0.3048)
						)
						(arc
							(start 0.2032 0.3048)
							(mid 0.275042 0.275042)
							(end 0.3048 0.2032)
						)
					)
					(width 0)
					(fill yes)
				)
			)
		)
		(pad "2" smd custom
			(at 0 0.4445 180)
			(size 0.1524 0.1524)
			(layers "F.Cu" "F.Mask" "F.Paste")
			(net "GND")
			(options
				(clearance outline)
				(anchor circle)
			)
			(primitives
				(gr_poly
					(pts
						(arc
							(start 0.3048 -0.2032)
							(mid 0.275042 -0.275042)
							(end 0.2032 -0.3048)
						)
						(arc
							(start -0.2032 -0.3048)
							(mid -0.275042 -0.275042)
							(end -0.3048 -0.2032)
						)
						(arc
							(start -0.3048 0.2032)
							(mid -0.275042 0.275042)
							(end -0.2032 0.3048)
						)
						(arc
							(start 0.2032 0.3048)
							(mid 0.275042 0.275042)
							(end 0.3048 0.2032)
						)
					)
					(width 0)
					(fill yes)
				)
			)
		)
	)
)
